(kicad_pcb
	(version 20260206)
	(generator "pcbnew")
	(generator_version "10.0")
	(general
		(thickness 1.6)
		(legacy_teardrops no)
	)
	(paper "A4")
	(title_block
		(title "panther-plus-userver — 13130-1b_20150205.brd")
		(comment 1 "Honey Badger (Wiwynn) / footprint 1214 of 1509 (DIMM3), pads 191-197 of 210")
	)
	(layers
		(0 "F.Cu" signal "TOP")
		(4 "In1.Cu" signal "L2")
		(6 "In2.Cu" signal "L3")
		(8 "In3.Cu" signal "L4")
		(10 "In4.Cu" signal "L5")
		(12 "In5.Cu" signal "L6")
		(14 "In6.Cu" signal "L7")
		(16 "In7.Cu" signal "L8")
		(18 "In8.Cu" signal "L9")
		(20 "In9.Cu" signal "L10")
		(22 "In10.Cu" signal "L11")
		(2 "B.Cu" signal "BOTTOM")
		(9 "F.Adhes" user "F.Adhesive")
		(11 "B.Adhes" user "B.Adhesive")
		(13 "F.Paste" user "Package Geometry/Pastemask Top")
		(15 "B.Paste" user "Package Geometry/Pastemask Bottom")
		(5 "F.SilkS" user "Ref Des/Silkscreen Top")
		(7 "B.SilkS" user "Ref Des/Silkscreen Bottom")
		(1 "F.Mask" user "Board Geometry/Soldermask Top")
		(3 "B.Mask" user "Board Geometry/Soldermask Bottom")
		(17 "Dwgs.User" user "User.Drawings")
		(19 "Cmts.User" user "User.Comments")
		(21 "Eco1.User" user "User.Eco1")
		(23 "Eco2.User" user "User.Eco2")
		(25 "Edge.Cuts" user "Board Geometry/Outline")
		(27 "Margin" user)
		(31 "F.CrtYd" user "Package Geometry/Place Bound Top")
		(29 "B.CrtYd" user "Package Geometry/Place Bound Bottom")
		(35 "F.Fab" user "Ref Des/Assembly Top")
		(33 "B.Fab" user "Ref Des/Assembly Bottom")
	)
	(footprint ""
		(layer "B.Cu")
		(at 159.999934 -5.790692)
		(property "Reference" "DIMM3"
			(at 0 0 0)
			(layer "B.SilkS")
			(hide yes)
			(effects
				(font
					(size 1.27 1.27)
				)
				(justify mirror)
			)
		)
		(property "Value" "DDR3-204P-142-COLAY-1-GP-U"
			(at 41.312338 -16.676878 0)
			(unlocked yes)
			(layer "B.Fab")
			(hide yes)
			(effects
				(font
					(size 1.016 1.016)
					(thickness 0.1524)
				)
				(justify mirror)
			)
		)
		(property "Device Type" "AS0A626-J8R6-7H-COLAY-1"
			(at 41.312338 -18.200878 0)
			(unlocked yes)
			(layer "B.Fab")
			(hide yes)
			(effects
				(font
					(size 1.016 1.016)
					(thickness 0.1524)
				)
				(justify mirror)
			)
		)
		(duplicate_pad_numbers_are_jumpers no)
		(pad "189" smd custom
			(at 27.15006 -4.100068 180)
			(size 0.1143 0.1143)
			(layers "B.Cu" "B.Mask" "B.Paste")
			(net "GND")
			(options
				(clearance outline)
				(anchor circle)
			)
			(primitives
				(gr_poly
					(pts
						(xy 0 -0.9017) (xy -0.03175 -0.89916) (xy -0.0635 -0.889) (xy -0.09144 -0.87376) (xy -0.11684 -0.85344)
						(xy -0.13716 -0.82804) (xy -0.1524 -0.8001) (xy -0.16256 -0.76835) (xy -0.1651 -0.7366) (xy -0.1651 -0.44958)
						(xy -0.17272 -0.44196) (xy -0.19812 -0.4064) (xy -0.2032 -0.39624) (xy -0.20701 -0.38735) (xy -0.21209 -0.37719)
						(xy -0.2159 -0.36703) (xy -0.21844 -0.35687) (xy -0.22225 -0.34544) (xy -0.22352 -0.33528) (xy -0.22606 -0.32512)
						(xy -0.22733 -0.31369) (xy -0.22733 -0.30353) (xy -0.2286 -0.2921) (xy -0.22733 -0.28067) (xy -0.22733 -0.27051)
						(xy -0.22606 -0.25908) (xy -0.22352 -0.24892) (xy -0.22225 -0.23876) (xy -0.21844 -0.22733) (xy -0.2159 -0.21717)
						(xy -0.21209 -0.20701) (xy -0.20701 -0.19685) (xy -0.2032 -0.18796) (xy -0.19812 -0.1778) (xy -0.17272 -0.14224)
						(xy -0.1651 -0.13462) (xy -0.1651 0.7366) (xy -0.16256 0.76835) (xy -0.1524 0.8001) (xy -0.13716 0.82804)
						(xy -0.11684 0.85344) (xy -0.09144 0.87376) (xy -0.0635 0.889) (xy -0.03175 0.89916) (xy 0 0.9017)
						(xy 0.03175 0.89916) (xy 0.0635 0.889) (xy 0.09144 0.87376) (xy 0.11684 0.85344) (xy 0.13716 0.82804)
						(xy 0.1524 0.8001) (xy 0.16256 0.76835) (xy 0.1651 0.7366) (xy 0.1651 -0.13462) (xy 0.17272 -0.14224)
						(xy 0.19812 -0.1778) (xy 0.2032 -0.18796) (xy 0.20701 -0.19685) (xy 0.21209 -0.20701) (xy 0.2159 -0.21717)
						(xy 0.21844 -0.22733) (xy 0.22225 -0.23876) (xy 0.22352 -0.24892) (xy 0.22606 -0.25908) (xy 0.22733 -0.27051)
						(xy 0.22733 -0.28067) (xy 0.2286 -0.2921) (xy 0.22733 -0.30353) (xy 0.22733 -0.31369) (xy 0.22606 -0.32512)
						(xy 0.22352 -0.33528) (xy 0.22225 -0.34544) (xy 0.21844 -0.35687) (xy 0.2159 -0.36703) (xy 0.21209 -0.37719)
						(xy 0.20701 -0.38735) (xy 0.2032 -0.39624) (xy 0.19812 -0.4064) (xy 0.17272 -0.44196) (xy 0.1651 -0.44958)
						(xy 0.1651 -0.7366) (xy 0.16256 -0.76835) (xy 0.1524 -0.8001) (xy 0.13716 -0.82804) (xy 0.11684 -0.85344)
						(xy 0.09144 -0.87376) (xy 0.0635 -0.889) (xy 0.03175 -0.89916)
					)
					(width 0)
					(fill yes)
				)
			)
		)
		(pad "190" smd custom
			(at 27.450034 4.100068 180)
			(size 0.1143 0.1143)
			(layers "B.Cu" "B.Mask" "B.Paste")
			(net "GND")
			(options
				(clearance outline)
				(anchor circle)
			)
			(primitives
				(gr_poly
					(pts
						(xy 0 -0.9017) (xy -0.03175 -0.89916) (xy -0.0635 -0.889) (xy -0.09144 -0.87376) (xy -0.11684 -0.85344)
						(xy -0.13716 -0.82804) (xy -0.1524 -0.8001) (xy -0.16256 -0.76835) (xy -0.1651 -0.7366) (xy -0.1651 0.13462)
						(xy -0.17272 0.14224) (xy -0.19812 0.1778) (xy -0.2032 0.18796) (xy -0.20701 0.19685) (xy -0.21209 0.20701)
						(xy -0.2159 0.21717) (xy -0.21844 0.22733) (xy -0.22225 0.23876) (xy -0.22352 0.24892) (xy -0.22606 0.25908)
						(xy -0.22733 0.27051) (xy -0.22733 0.28067) (xy -0.2286 0.2921) (xy -0.22733 0.30353) (xy -0.22733 0.31369)
						(xy -0.22606 0.32512) (xy -0.22352 0.33528) (xy -0.22225 0.34544) (xy -0.21844 0.35687) (xy -0.2159 0.36703)
						(xy -0.21209 0.37719) (xy -0.20701 0.38735) (xy -0.2032 0.39624) (xy -0.19812 0.4064) (xy -0.17272 0.44196)
						(xy -0.1651 0.44958) (xy -0.1651 0.7366) (xy -0.16256 0.76835) (xy -0.1524 0.8001) (xy -0.13716 0.82804)
						(xy -0.11684 0.85344) (xy -0.09144 0.87376) (xy -0.0635 0.889) (xy -0.03175 0.89916) (xy 0 0.9017)
						(xy 0.03175 0.89916) (xy 0.0635 0.889) (xy 0.09144 0.87376) (xy 0.11684 0.85344) (xy 0.13716 0.82804)
						(xy 0.1524 0.8001) (xy 0.16256 0.76835) (xy 0.1651 0.7366) (xy 0.1651 0.44958) (xy 0.17272 0.44196)
						(xy 0.19812 0.4064) (xy 0.2032 0.39624) (xy 0.20701 0.38735) (xy 0.21209 0.37719) (xy 0.2159 0.36703)
						(xy 0.21844 0.35687) (xy 0.22225 0.34544) (xy 0.22352 0.33528) (xy 0.22606 0.32512) (xy 0.22733 0.31369)
						(xy 0.22733 0.30353) (xy 0.2286 0.2921) (xy 0.22733 0.28067) (xy 0.22733 0.27051) (xy 0.22606 0.25908)
						(xy 0.22352 0.24892) (xy 0.22225 0.23876) (xy 0.21844 0.22733) (xy 0.2159 0.21717) (xy 0.21209 0.20701)
						(xy 0.20701 0.19685) (xy 0.2032 0.18796) (xy 0.19812 0.1778) (xy 0.17272 0.14224) (xy 0.1651 0.13462)
						(xy 0.1651 -0.7366) (xy 0.16256 -0.76835) (xy 0.1524 -0.8001) (xy 0.13716 -0.82804) (xy 0.11684 -0.85344)
						(xy 0.09144 -0.87376) (xy 0.0635 -0.889) (xy 0.03175 -0.89916)
					)
					(width 0)
					(fill yes)
				)
			)
		)
		(pad "191" smd custom
			(at 27.750008 -4.100068 180)
			(size 0.1143 0.1143)
			(layers "B.Cu" "B.Mask" "B.Paste")
			(net "M_B_DQ58")
			(options
				(clearance outline)
				(anchor circle)
			)
			(primitives
				(gr_poly
					(pts
						(xy 0 -0.9017) (xy -0.03175 -0.89916) (xy -0.0635 -0.889) (xy -0.09144 -0.87376) (xy -0.11684 -0.85344)
						(xy -0.13716 -0.82804) (xy -0.1524 -0.8001) (xy -0.16256 -0.76835) (xy -0.1651 -0.7366) (xy -0.1651 -0.19685)
						(xy -0.17272 -0.18923) (xy -0.17907 -0.18034) (xy -0.18669 -0.17145) (xy -0.19177 -0.16256) (xy -0.19812 -0.15367)
						(xy -0.20828 -0.13335) (xy -0.21971 -0.10287) (xy -0.22225 -0.09271) (xy -0.22479 -0.08128) (xy -0.22606 -0.07112)
						(xy -0.2286 -0.05969) (xy -0.2286 -0.01651) (xy -0.22606 -0.00508) (xy -0.22479 0.00508) (xy -0.22225 0.01651)
						(xy -0.21971 0.02667) (xy -0.20828 0.05715) (xy -0.19812 0.07747) (xy -0.19177 0.08636) (xy -0.18669 0.09525)
						(xy -0.17907 0.10414) (xy -0.17272 0.11303) (xy -0.1651 0.12065) (xy -0.1651 0.7366) (xy -0.16256 0.76835)
						(xy -0.1524 0.8001) (xy -0.13716 0.82804) (xy -0.11684 0.85344) (xy -0.09144 0.87376) (xy -0.0635 0.889)
						(xy -0.03175 0.89916) (xy 0 0.9017) (xy 0.03175 0.89916) (xy 0.0635 0.889) (xy 0.09144 0.87376)
						(xy 0.11684 0.85344) (xy 0.13716 0.82804) (xy 0.1524 0.8001) (xy 0.16256 0.76835) (xy 0.1651 0.7366)
						(xy 0.1651 0.11938) (xy 0.17272 0.11176) (xy 0.19812 0.0762) (xy 0.2032 0.06604) (xy 0.20701 0.05715)
						(xy 0.21209 0.04699) (xy 0.2159 0.03683) (xy 0.21844 0.02667) (xy 0.22225 0.01524) (xy 0.22352 0.00508)
						(xy 0.22606 -0.00508) (xy 0.22733 -0.01651) (xy 0.22733 -0.02667) (xy 0.2286 -0.0381) (xy 0.22733 -0.04953)
						(xy 0.22733 -0.05969) (xy 0.22606 -0.07112) (xy 0.22352 -0.08128) (xy 0.22225 -0.09144) (xy 0.21844 -0.10287)
						(xy 0.2159 -0.11303) (xy 0.21209 -0.12319) (xy 0.20701 -0.13335) (xy 0.2032 -0.14224) (xy 0.19812 -0.1524)
						(xy 0.17272 -0.18796) (xy 0.1651 -0.19558) (xy 0.1651 -0.7366) (xy 0.16256 -0.76835) (xy 0.1524 -0.8001)
						(xy 0.13716 -0.82804) (xy 0.11684 -0.85344) (xy 0.09144 -0.87376) (xy 0.0635 -0.889) (xy 0.03175 -0.89916)
					)
					(width 0)
					(fill yes)
				)
			)
		)
		(pad "192" smd custom
			(at 28.049982 4.100068 180)
			(size 0.1143 0.1143)
			(layers "B.Cu" "B.Mask" "B.Paste")
			(net "M_B_DQ62")
			(options
				(clearance outline)
				(anchor circle)
			)
			(primitives
				(gr_poly
					(pts
						(xy 0 -0.9017) (xy -0.03175 -0.89916) (xy -0.0635 -0.889) (xy -0.09144 -0.87376) (xy -0.11684 -0.85344)
						(xy -0.13716 -0.82804) (xy -0.1524 -0.8001) (xy -0.16256 -0.76835) (xy -0.1651 -0.7366) (xy -0.1651 -0.11938)
						(xy -0.17272 -0.11176) (xy -0.19812 -0.0762) (xy -0.2032 -0.06604) (xy -0.20701 -0.05715) (xy -0.21209 -0.04699)
						(xy -0.2159 -0.03683) (xy -0.21844 -0.02667) (xy -0.22225 -0.01524) (xy -0.22352 -0.00508) (xy -0.22606 0.00508)
						(xy -0.22733 0.01651) (xy -0.22733 0.02667) (xy -0.2286 0.0381) (xy -0.22733 0.04953) (xy -0.22733 0.05969)
						(xy -0.22606 0.07112) (xy -0.22352 0.08128) (xy -0.22225 0.09144) (xy -0.21844 0.10287) (xy -0.2159 0.11303)
						(xy -0.21209 0.12319) (xy -0.20701 0.13335) (xy -0.2032 0.14224) (xy -0.19812 0.1524) (xy -0.17272 0.18796)
						(xy -0.1651 0.19558) (xy -0.1651 0.7366) (xy -0.16256 0.76835) (xy -0.1524 0.8001) (xy -0.13716 0.82804)
						(xy -0.11684 0.85344) (xy -0.09144 0.87376) (xy -0.0635 0.889) (xy -0.03175 0.89916) (xy 0 0.9017)
						(xy 0.03175 0.89916) (xy 0.0635 0.889) (xy 0.09144 0.87376) (xy 0.11684 0.85344) (xy 0.13716 0.82804)
						(xy 0.1524 0.8001) (xy 0.16256 0.76835) (xy 0.1651 0.7366) (xy 0.1651 0.19685) (xy 0.17272 0.18923)
						(xy 0.17907 0.18034) (xy 0.18669 0.17145) (xy 0.19177 0.16256) (xy 0.19812 0.15367) (xy 0.20828 0.13335)
						(xy 0.21971 0.10287) (xy 0.22225 0.09271) (xy 0.22479 0.08128) (xy 0.22606 0.07112) (xy 0.2286 0.05969)
						(xy 0.2286 0.01651) (xy 0.22606 0.00508) (xy 0.22479 -0.00508) (xy 0.22225 -0.01651) (xy 0.21971 -0.02667)
						(xy 0.20828 -0.05715) (xy 0.19812 -0.07747) (xy 0.19177 -0.08636) (xy 0.18669 -0.09525) (xy 0.17907 -0.10414)
						(xy 0.17272 -0.11303) (xy 0.1651 -0.12065) (xy 0.1651 -0.7366) (xy 0.16256 -0.76835) (xy 0.1524 -0.8001)
						(xy 0.13716 -0.82804) (xy 0.11684 -0.85344) (xy 0.09144 -0.87376) (xy 0.0635 -0.889) (xy 0.03175 -0.89916)
					)
					(width 0)
					(fill yes)
				)
			)
		)
		(pad "193" smd custom
			(at 28.349956 -4.100068 180)
			(size 0.1143 0.1143)
			(layers "B.Cu" "B.Mask" "B.Paste")
			(net "M_B_DQ59")
			(options
				(clearance outline)
				(anchor circle)
			)
			(primitives
				(gr_poly
					(pts
						(xy 0 -0.9017) (xy -0.03175 -0.89916) (xy -0.0635 -0.889) (xy -0.09144 -0.87376) (xy -0.11684 -0.85344)
						(xy -0.13716 -0.82804) (xy -0.1524 -0.8001) (xy -0.16256 -0.76835) (xy -0.1651 -0.7366) (xy -0.1651 -0.44958)
						(xy -0.17272 -0.44196) (xy -0.19812 -0.4064) (xy -0.2032 -0.39624) (xy -0.20701 -0.38735) (xy -0.21209 -0.37719)
						(xy -0.2159 -0.36703) (xy -0.21844 -0.35687) (xy -0.22225 -0.34544) (xy -0.22352 -0.33528) (xy -0.22606 -0.32512)
						(xy -0.22733 -0.31369) (xy -0.22733 -0.30353) (xy -0.2286 -0.2921) (xy -0.22733 -0.28067) (xy -0.22733 -0.27051)
						(xy -0.22606 -0.25908) (xy -0.22352 -0.24892) (xy -0.22225 -0.23876) (xy -0.21844 -0.22733) (xy -0.2159 -0.21717)
						(xy -0.21209 -0.20701) (xy -0.20701 -0.19685) (xy -0.2032 -0.18796) (xy -0.19812 -0.1778) (xy -0.17272 -0.14224)
						(xy -0.1651 -0.13462) (xy -0.1651 0.7366) (xy -0.16256 0.76835) (xy -0.1524 0.8001) (xy -0.13716 0.82804)
						(xy -0.11684 0.85344) (xy -0.09144 0.87376) (xy -0.0635 0.889) (xy -0.03175 0.89916) (xy 0 0.9017)
						(xy 0.03175 0.89916) (xy 0.0635 0.889) (xy 0.09144 0.87376) (xy 0.11684 0.85344) (xy 0.13716 0.82804)
						(xy 0.1524 0.8001) (xy 0.16256 0.76835) (xy 0.1651 0.7366) (xy 0.1651 -0.13462) (xy 0.17272 -0.14224)
						(xy 0.19812 -0.1778) (xy 0.2032 -0.18796) (xy 0.20701 -0.19685) (xy 0.21209 -0.20701) (xy 0.2159 -0.21717)
						(xy 0.21844 -0.22733) (xy 0.22225 -0.23876) (xy 0.22352 -0.24892) (xy 0.22606 -0.25908) (xy 0.22733 -0.27051)
						(xy 0.22733 -0.28067) (xy 0.2286 -0.2921) (xy 0.22733 -0.30353) (xy 0.22733 -0.31369) (xy 0.22606 -0.32512)
						(xy 0.22352 -0.33528) (xy 0.22225 -0.34544) (xy 0.21844 -0.35687) (xy 0.2159 -0.36703) (xy 0.21209 -0.37719)
						(xy 0.20701 -0.38735) (xy 0.2032 -0.39624) (xy 0.19812 -0.4064) (xy 0.17272 -0.44196) (xy 0.1651 -0.44958)
						(xy 0.1651 -0.7366) (xy 0.16256 -0.76835) (xy 0.1524 -0.8001) (xy 0.13716 -0.82804) (xy 0.11684 -0.85344)
						(xy 0.09144 -0.87376) (xy 0.0635 -0.889) (xy 0.03175 -0.89916)
					)
					(width 0)
					(fill yes)
				)
			)
		)
		(pad "194" smd custom
			(at 28.64993 4.100068 180)
			(size 0.1143 0.1143)
			(layers "B.Cu" "B.Mask" "B.Paste")
			(net "M_B_DQ63")
			(options
				(clearance outline)
				(anchor circle)
			)
			(primitives
				(gr_poly
					(pts
						(xy 0 -0.9017) (xy -0.03175 -0.89916) (xy -0.0635 -0.889) (xy -0.09144 -0.87376) (xy -0.11684 -0.85344)
						(xy -0.13716 -0.82804) (xy -0.1524 -0.8001) (xy -0.16256 -0.76835) (xy -0.1651 -0.7366) (xy -0.1651 0.13462)
						(xy -0.17272 0.14224) (xy -0.19812 0.1778) (xy -0.2032 0.18796) (xy -0.20701 0.19685) (xy -0.21209 0.20701)
						(xy -0.2159 0.21717) (xy -0.21844 0.22733) (xy -0.22225 0.23876) (xy -0.22352 0.24892) (xy -0.22606 0.25908)
						(xy -0.22733 0.27051) (xy -0.22733 0.28067) (xy -0.2286 0.2921) (xy -0.22733 0.30353) (xy -0.22733 0.31369)
						(xy -0.22606 0.32512) (xy -0.22352 0.33528) (xy -0.22225 0.34544) (xy -0.21844 0.35687) (xy -0.2159 0.36703)
						(xy -0.21209 0.37719) (xy -0.20701 0.38735) (xy -0.2032 0.39624) (xy -0.19812 0.4064) (xy -0.17272 0.44196)
						(xy -0.1651 0.44958) (xy -0.1651 0.7366) (xy -0.16256 0.76835) (xy -0.1524 0.8001) (xy -0.13716 0.82804)
						(xy -0.11684 0.85344) (xy -0.09144 0.87376) (xy -0.0635 0.889) (xy -0.03175 0.89916) (xy 0 0.9017)
						(xy 0.03175 0.89916) (xy 0.0635 0.889) (xy 0.09144 0.87376) (xy 0.11684 0.85344) (xy 0.13716 0.82804)
						(xy 0.1524 0.8001) (xy 0.16256 0.76835) (xy 0.1651 0.7366) (xy 0.1651 0.44958) (xy 0.17272 0.44196)
						(xy 0.19812 0.4064) (xy 0.2032 0.39624) (xy 0.20701 0.38735) (xy 0.21209 0.37719) (xy 0.2159 0.36703)
						(xy 0.21844 0.35687) (xy 0.22225 0.34544) (xy 0.22352 0.33528) (xy 0.22606 0.32512) (xy 0.22733 0.31369)
						(xy 0.22733 0.30353) (xy 0.2286 0.2921) (xy 0.22733 0.28067) (xy 0.22733 0.27051) (xy 0.22606 0.25908)
						(xy 0.22352 0.24892) (xy 0.22225 0.23876) (xy 0.21844 0.22733) (xy 0.2159 0.21717) (xy 0.21209 0.20701)
						(xy 0.20701 0.19685) (xy 0.2032 0.18796) (xy 0.19812 0.1778) (xy 0.17272 0.14224) (xy 0.1651 0.13462)
						(xy 0.1651 -0.7366) (xy 0.16256 -0.76835) (xy 0.1524 -0.8001) (xy 0.13716 -0.82804) (xy 0.11684 -0.85344)
						(xy 0.09144 -0.87376) (xy 0.0635 -0.889) (xy 0.03175 -0.89916)
					)
					(width 0)
					(fill yes)
				)
			)
		)
		(pad "195" smd custom
			(at 28.949904 -4.100068 180)
			(size 0.1143 0.1143)
			(layers "B.Cu" "B.Mask" "B.Paste")
			(net "GND")
			(options
				(clearance outline)
				(anchor circle)
			)
			(primitives
				(gr_poly
					(pts
						(xy 0 -0.9017) (xy -0.03175 -0.89916) (xy -0.0635 -0.889) (xy -0.09144 -0.87376) (xy -0.11684 -0.85344)
						(xy -0.13716 -0.82804) (xy -0.1524 -0.8001) (xy -0.16256 -0.76835) (xy -0.1651 -0.7366) (xy -0.1651 -0.19685)
						(xy -0.17272 -0.18923) (xy -0.17907 -0.18034) (xy -0.18669 -0.17145) (xy -0.19177 -0.16256) (xy -0.19812 -0.15367)
						(xy -0.20828 -0.13335) (xy -0.21971 -0.10287) (xy -0.22225 -0.09271) (xy -0.22479 -0.08128) (xy -0.22606 -0.07112)
						(xy -0.2286 -0.05969) (xy -0.2286 -0.01651) (xy -0.22606 -0.00508) (xy -0.22479 0.00508) (xy -0.22225 0.01651)
						(xy -0.21971 0.02667) (xy -0.20828 0.05715) (xy -0.19812 0.07747) (xy -0.19177 0.08636) (xy -0.18669 0.09525)
						(xy -0.17907 0.10414) (xy -0.17272 0.11303) (xy -0.1651 0.12065) (xy -0.1651 0.7366) (xy -0.16256 0.76835)
						(xy -0.1524 0.8001) (xy -0.13716 0.82804) (xy -0.11684 0.85344) (xy -0.09144 0.87376) (xy -0.0635 0.889)
						(xy -0.03175 0.89916) (xy 0 0.9017) (xy 0.03175 0.89916) (xy 0.0635 0.889) (xy 0.09144 0.87376)
						(xy 0.11684 0.85344) (xy 0.13716 0.82804) (xy 0.1524 0.8001) (xy 0.16256 0.76835) (xy 0.1651 0.7366)
						(xy 0.1651 0.11938) (xy 0.17272 0.11176) (xy 0.19812 0.0762) (xy 0.2032 0.06604) (xy 0.20701 0.05715)
						(xy 0.21209 0.04699) (xy 0.2159 0.03683) (xy 0.21844 0.02667) (xy 0.22225 0.01524) (xy 0.22352 0.00508)
						(xy 0.22606 -0.00508) (xy 0.22733 -0.01651) (xy 0.22733 -0.02667) (xy 0.2286 -0.0381) (xy 0.22733 -0.04953)
						(xy 0.22733 -0.05969) (xy 0.22606 -0.07112) (xy 0.22352 -0.08128) (xy 0.22225 -0.09144) (xy 0.21844 -0.10287)
						(xy 0.2159 -0.11303) (xy 0.21209 -0.12319) (xy 0.20701 -0.13335) (xy 0.2032 -0.14224) (xy 0.19812 -0.1524)
						(xy 0.17272 -0.18796) (xy 0.1651 -0.19558) (xy 0.1651 -0.7366) (xy 0.16256 -0.76835) (xy 0.1524 -0.8001)
						(xy 0.13716 -0.82804) (xy 0.11684 -0.85344) (xy 0.09144 -0.87376) (xy 0.0635 -0.889) (xy 0.03175 -0.89916)
					)
					(width 0)
					(fill yes)
				)
			)
		)
	)
)
